(kicad_pcb
	(version 20260206)
	(generator "pcbnew")
	(generator_version "10.0")
	(general
		(thickness 1.6)
		(legacy_teardrops no)
	)
	(paper "A4")
	(title_block
		(title "03242023_DA0F0TMBIJ0_F0T_Motherboard_J_brd_V01_OCP.brd")
		(comment 1 "Grand Teton / footprints 4528-4534 of 6105")
	)
	(layers
		(0 "F.Cu" signal "TOP")
		(4 "In1.Cu" signal "GND")
		(6 "In2.Cu" signal "IN1")
		(8 "In3.Cu" signal "GND1")
		(10 "In4.Cu" signal "IN2")
		(12 "In5.Cu" signal "GND2")
		(14 "In6.Cu" signal "IN3")
		(16 "In7.Cu" signal "GND3")
		(18 "In8.Cu" signal "VCC")
		(20 "In9.Cu" signal "VCC1")
		(22 "In10.Cu" signal "GND4")
		(24 "In11.Cu" signal "IN4")
		(26 "In12.Cu" signal "GND5")
		(28 "In13.Cu" signal "IN5")
		(30 "In14.Cu" signal "GND6")
		(32 "In15.Cu" signal "IN6")
		(34 "In16.Cu" signal "GND7")
		(2 "B.Cu" signal "BOTTOM")
		(9 "F.Adhes" user "F.Adhesive")
		(11 "B.Adhes" user "B.Adhesive")
		(13 "F.Paste" user "Package Geometry/Pastemask Top")
		(15 "B.Paste" user "Package Geometry/Pastemask Bottom")
		(5 "F.SilkS" user "Ref Des/Silkscreen Top")
		(7 "B.SilkS" user "Ref Des/Silkscreen Bottom")
		(1 "F.Mask" user "Board Geometry/Soldermask Top")
		(3 "B.Mask" user "Board Geometry/Soldermask Bottom")
		(17 "Dwgs.User" user "User.Drawings")
		(19 "Cmts.User" user "User.Comments")
		(21 "Eco1.User" user "User.Eco1")
		(23 "Eco2.User" user "User.Eco2")
		(25 "Edge.Cuts" user "Board Geometry/Outline")
		(27 "Margin" user)
		(31 "F.CrtYd" user "Package Geometry/Place Bound Top")
		(29 "B.CrtYd" user "Package Geometry/Place Bound Bottom")
		(35 "F.Fab" user "Ref Des/Assembly Top")
		(33 "B.Fab" user "Ref Des/Assembly Bottom")
	)
	(footprint ""
		(layer "B.Cu")
		(at 44.821856 -353.567492 90)
		(property "Reference" "PC1200_P1_4"
			(at 0 0 90)
			(layer "B.SilkS")
			(hide yes)
			(effects
				(font
					(size 1.27 1.27)
				)
				(justify mirror)
			)
		)
		(property "Value" ""
			(at 0 0 90)
			(layer "B.Fab")
			(effects
				(font
					(size 1.27 1.27)
				)
				(justify mirror)
			)
		)
		(duplicate_pad_numbers_are_jumpers no)
		(fp_line
			(start 1.524 -0.762)
			(end -1.524 -0.762)
			(stroke
				(width 0.1524)
				(type default)
			)
			(layer "B.SilkS")
		)
		(fp_line
			(start -1.524 -0.762)
			(end -1.524 0.762)
			(stroke
				(width 0.1524)
				(type default)
			)
			(layer "B.SilkS")
		)
		(fp_line
			(start 1.524 0.762)
			(end 1.524 -0.762)
			(stroke
				(width 0.1524)
				(type default)
			)
			(layer "B.SilkS")
		)
		(fp_line
			(start -1.524 0.762)
			(end 1.524 0.762)
			(stroke
				(width 0.1524)
				(type default)
			)
			(layer "B.SilkS")
		)
		(fp_line
			(start 1.1049 -0.724916)
			(end 1.1049 0.724916)
			(stroke
				(width 0.1)
				(type default)
			)
			(layer "B.Fab")
		)
		(fp_line
			(start -1.1049 -0.724916)
			(end 1.1049 -0.724916)
			(stroke
				(width 0.1)
				(type default)
			)
			(layer "B.Fab")
		)
		(fp_line
			(start 1.1049 0.724916)
			(end -1.1049 0.724916)
			(stroke
				(width 0.1)
				(type default)
			)
			(layer "B.Fab")
		)
		(fp_line
			(start -1.1049 0.724916)
			(end -1.1049 -0.724916)
			(stroke
				(width 0.1)
				(type default)
			)
			(layer "B.Fab")
		)
		(pad "1" smd rect
			(at 0.889 0 90)
			(size 1.016 1.27)
			(layers "B.Cu" "B.Mask" "B.Paste")
			(net "SW_P12V_PVCCFA_EHV_FIVRA_CPU1_L")
		)
		(pad "2" smd rect
			(at -0.889 0 90)
			(size 1.016 1.27)
			(layers "B.Cu" "B.Mask" "B.Paste")
			(net "GND")
		)
	)
	(footprint ""
		(layer "B.Cu")
		(at 297.876468 -196.191378 -90)
		(property "Reference" "R4295"
			(at 0 0 90)
			(layer "B.SilkS")
			(hide yes)
			(effects
				(font
					(size 1.27 1.27)
				)
				(justify mirror)
			)
		)
		(property "Value" ""
			(at 0 0 90)
			(layer "B.Fab")
			(effects
				(font
					(size 1.27 1.27)
				)
				(justify mirror)
			)
		)
		(duplicate_pad_numbers_are_jumpers no)
		(fp_line
			(start -0.7874 0.4064)
			(end 0.7874 0.4064)
			(stroke
				(width 0.1524)
				(type default)
			)
			(layer "B.SilkS")
		)
		(fp_line
			(start 0.7874 0.4064)
			(end 0.7874 -0.4064)
			(stroke
				(width 0.1524)
				(type default)
			)
			(layer "B.SilkS")
		)
		(fp_line
			(start -0.7874 -0.4064)
			(end -0.7874 0.4064)
			(stroke
				(width 0.1524)
				(type default)
			)
			(layer "B.SilkS")
		)
		(fp_line
			(start 0.7874 -0.4064)
			(end -0.7874 -0.4064)
			(stroke
				(width 0.1524)
				(type default)
			)
			(layer "B.SilkS")
		)
		(fp_line
			(start -0.67945 0.3048)
			(end -0.120396 0.3048)
			(stroke
				(width 0.1)
				(type default)
			)
			(layer "B.Fab")
		)
		(fp_line
			(start -0.120396 0.3048)
			(end -0.120396 0.2794)
			(stroke
				(width 0.1)
				(type default)
			)
			(layer "B.Fab")
		)
		(fp_line
			(start 0.12065 0.3048)
			(end 0.67945 0.3048)
			(stroke
				(width 0.1)
				(type default)
			)
			(layer "B.Fab")
		)
		(fp_line
			(start 0.67945 0.3048)
			(end 0.67945 -0.305054)
			(stroke
				(width 0.1)
				(type default)
			)
			(layer "B.Fab")
		)
		(fp_line
			(start -0.120396 0.2794)
			(end 0.12065 0.2794)
			(stroke
				(width 0.1)
				(type default)
			)
			(layer "B.Fab")
		)
		(fp_line
			(start 0.12065 0.2794)
			(end 0.12065 0.3048)
			(stroke
				(width 0.1)
				(type default)
			)
			(layer "B.Fab")
		)
		(fp_line
			(start -0.12065 -0.2794)
			(end -0.12065 -0.3048)
			(stroke
				(width 0.1)
				(type default)
			)
			(layer "B.Fab")
		)
		(fp_line
			(start 0.12065 -0.2794)
			(end -0.12065 -0.2794)
			(stroke
				(width 0.1)
				(type default)
			)
			(layer "B.Fab")
		)
		(fp_line
			(start -0.67945 -0.3048)
			(end -0.67945 0.3048)
			(stroke
				(width 0.1)
				(type default)
			)
			(layer "B.Fab")
		)
		(fp_line
			(start -0.12065 -0.3048)
			(end -0.67945 -0.3048)
			(stroke
				(width 0.1)
				(type default)
			)
			(layer "B.Fab")
		)
		(fp_line
			(start 0.12065 -0.305054)
			(end 0.12065 -0.2794)
			(stroke
				(width 0.1)
				(type default)
			)
			(layer "B.Fab")
		)
		(fp_line
			(start 0.67945 -0.305054)
			(end 0.12065 -0.305054)
			(stroke
				(width 0.1)
				(type default)
			)
			(layer "B.Fab")
		)
		(pad "1" smd circle
			(at 0.40005 0 90)
			(size 0 0)
			(layers "B.Cu" "B.Mask" "B.Paste")
			(net "PWRGD_DRAMPWRGD_CPU0_AB_LVC1_R2")
		)
		(pad "2" smd circle
			(at -0.40005 0 90)
			(size 0 0)
			(layers "B.Cu" "B.Mask" "B.Paste")
			(net "PWRGD_DRAMPWRGD_CPU0_AB_LVC1_R")
		)
	)
	(footprint ""
		(layer "B.Cu")
		(at 312.189622 -29.708348 180)
		(property "Reference" "R1198"
			(at 0 0 0)
			(layer "B.SilkS")
			(hide yes)
			(effects
				(font
					(size 1.27 1.27)
				)
				(justify mirror)
			)
		)
		(property "Value" ""
			(at 0 0 0)
			(layer "B.Fab")
			(effects
				(font
					(size 1.27 1.27)
				)
				(justify mirror)
			)
		)
		(duplicate_pad_numbers_are_jumpers no)
		(fp_line
			(start 0.7874 0.4064)
			(end 0.7874 -0.4064)
			(stroke
				(width 0.1524)
				(type default)
			)
			(layer "B.SilkS")
		)
		(fp_line
			(start 0.7874 -0.4064)
			(end -0.7874 -0.4064)
			(stroke
				(width 0.1524)
				(type default)
			)
			(layer "B.SilkS")
		)
		(fp_line
			(start -0.7874 0.4064)
			(end 0.7874 0.4064)
			(stroke
				(width 0.1524)
				(type default)
			)
			(layer "B.SilkS")
		)
		(fp_line
			(start -0.7874 -0.4064)
			(end -0.7874 0.4064)
			(stroke
				(width 0.1524)
				(type default)
			)
			(layer "B.SilkS")
		)
		(fp_line
			(start 0.67945 0.3048)
			(end 0.67945 -0.305054)
			(stroke
				(width 0.1)
				(type default)
			)
			(layer "B.Fab")
		)
		(fp_line
			(start 0.67945 -0.305054)
			(end 0.12065 -0.305054)
			(stroke
				(width 0.1)
				(type default)
			)
			(layer "B.Fab")
		)
		(fp_line
			(start 0.12065 0.3048)
			(end 0.67945 0.3048)
			(stroke
				(width 0.1)
				(type default)
			)
			(layer "B.Fab")
		)
		(fp_line
			(start 0.12065 0.2794)
			(end 0.12065 0.3048)
			(stroke
				(width 0.1)
				(type default)
			)
			(layer "B.Fab")
		)
		(fp_line
			(start 0.12065 -0.2794)
			(end -0.12065 -0.2794)
			(stroke
				(width 0.1)
				(type default)
			)
			(layer "B.Fab")
		)
		(fp_line
			(start 0.12065 -0.305054)
			(end 0.12065 -0.2794)
			(stroke
				(width 0.1)
				(type default)
			)
			(layer "B.Fab")
		)
		(fp_line
			(start -0.120396 0.3048)
			(end -0.120396 0.2794)
			(stroke
				(width 0.1)
				(type default)
			)
			(layer "B.Fab")
		)
		(fp_line
			(start -0.120396 0.2794)
			(end 0.12065 0.2794)
			(stroke
				(width 0.1)
				(type default)
			)
			(layer "B.Fab")
		)
		(fp_line
			(start -0.12065 -0.2794)
			(end -0.12065 -0.3048)
			(stroke
				(width 0.1)
				(type default)
			)
			(layer "B.Fab")
		)
		(fp_line
			(start -0.12065 -0.3048)
			(end -0.67945 -0.3048)
			(stroke
				(width 0.1)
				(type default)
			)
			(layer "B.Fab")
		)
		(fp_line
			(start -0.67945 0.3048)
			(end -0.120396 0.3048)
			(stroke
				(width 0.1)
				(type default)
			)
			(layer "B.Fab")
		)
		(fp_line
			(start -0.67945 -0.3048)
			(end -0.67945 0.3048)
			(stroke
				(width 0.1)
				(type default)
			)
			(layer "B.Fab")
		)
		(pad "1" smd circle
			(at 0.40005 0)
			(size 0 0)
			(layers "B.Cu" "B.Mask" "B.Paste")
			(net "P3V3_AUX")
		)
		(pad "2" smd circle
			(at -0.40005 0)
			(size 0 0)
			(layers "B.Cu" "B.Mask" "B.Paste")
			(net "PU_ACPRESENT")
		)
	)
	(footprint ""
		(layer "B.Cu")
		(at 98.052382 -333.639922 90)
		(property "Reference" "PC571_P1_1"
			(at 0 0 90)
			(layer "B.SilkS")
			(hide yes)
			(effects
				(font
					(size 1.27 1.27)
				)
				(justify mirror)
			)
		)
		(property "Value" ""
			(at 0 0 90)
			(layer "B.Fab")
			(effects
				(font
					(size 1.27 1.27)
				)
				(justify mirror)
			)
		)
		(duplicate_pad_numbers_are_jumpers no)
		(fp_line
			(start 1.524 -0.762)
			(end -1.524 -0.762)
			(stroke
				(width 0.1524)
				(type default)
			)
			(layer "B.SilkS")
		)
		(fp_line
			(start -1.524 -0.762)
			(end -1.524 0.762)
			(stroke
				(width 0.1524)
				(type default)
			)
			(layer "B.SilkS")
		)
		(fp_line
			(start 1.524 0.762)
			(end 1.524 -0.762)
			(stroke
				(width 0.1524)
				(type default)
			)
			(layer "B.SilkS")
		)
		(fp_line
			(start -1.524 0.762)
			(end 1.524 0.762)
			(stroke
				(width 0.1524)
				(type default)
			)
			(layer "B.SilkS")
		)
		(fp_line
			(start 1.1049 -0.724916)
			(end 1.1049 0.724916)
			(stroke
				(width 0.1)
				(type default)
			)
			(layer "B.Fab")
		)
		(fp_line
			(start -1.1049 -0.724916)
			(end 1.1049 -0.724916)
			(stroke
				(width 0.1)
				(type default)
			)
			(layer "B.Fab")
		)
		(fp_line
			(start 1.1049 0.724916)
			(end -1.1049 0.724916)
			(stroke
				(width 0.1)
				(type default)
			)
			(layer "B.Fab")
		)
		(fp_line
			(start -1.1049 0.724916)
			(end -1.1049 -0.724916)
			(stroke
				(width 0.1)
				(type default)
			)
			(layer "B.Fab")
		)
		(pad "1" smd rect
			(at 0.889 0 90)
			(size 1.016 1.27)
			(layers "B.Cu" "B.Mask" "B.Paste")
			(net "SW_P12V_PVCCIN_CPU1_FLT")
		)
		(pad "2" smd rect
			(at -0.889 0 90)
			(size 1.016 1.27)
			(layers "B.Cu" "B.Mask" "B.Paste")
			(net "GND")
		)
	)
	(footprint ""
		(layer "B.Cu")
		(at 421.304466 -193.353436 -90)
		(property "Reference" "C624"
			(at 0 0 90)
			(layer "B.SilkS")
			(hide yes)
			(effects
				(font
					(size 1.27 1.27)
				)
				(justify mirror)
			)
		)
		(property "Value" ""
			(at 0 0 90)
			(layer "B.Fab")
			(effects
				(font
					(size 1.27 1.27)
				)
				(justify mirror)
			)
		)
		(duplicate_pad_numbers_are_jumpers no)
		(fp_line
			(start -0.7874 0.4064)
			(end 0.7874 0.4064)
			(stroke
				(width 0.1524)
				(type default)
			)
			(layer "B.SilkS")
		)
		(fp_line
			(start 0.7874 0.4064)
			(end 0.7874 -0.4064)
			(stroke
				(width 0.1524)
				(type default)
			)
			(layer "B.SilkS")
		)
		(fp_line
			(start -0.7874 -0.4064)
			(end -0.7874 0.4064)
			(stroke
				(width 0.1524)
				(type default)
			)
			(layer "B.SilkS")
		)
		(fp_line
			(start 0.7874 -0.4064)
			(end -0.7874 -0.4064)
			(stroke
				(width 0.1524)
				(type default)
			)
			(layer "B.SilkS")
		)
		(fp_line
			(start -0.67945 0.3048)
			(end -0.120396 0.3048)
			(stroke
				(width 0.1)
				(type default)
			)
			(layer "B.Fab")
		)
		(fp_line
			(start -0.120396 0.3048)
			(end -0.120396 0.2794)
			(stroke
				(width 0.1)
				(type default)
			)
			(layer "B.Fab")
		)
		(fp_line
			(start 0.12065 0.3048)
			(end 0.67945 0.3048)
			(stroke
				(width 0.1)
				(type default)
			)
			(layer "B.Fab")
		)
		(fp_line
			(start 0.67945 0.3048)
			(end 0.67945 -0.305054)
			(stroke
				(width 0.1)
				(type default)
			)
			(layer "B.Fab")
		)
		(fp_line
			(start -0.120396 0.2794)
			(end 0.12065 0.2794)
			(stroke
				(width 0.1)
				(type default)
			)
			(layer "B.Fab")
		)
		(fp_line
			(start 0.12065 0.2794)
			(end 0.12065 0.3048)
			(stroke
				(width 0.1)
				(type default)
			)
			(layer "B.Fab")
		)
		(fp_line
			(start -0.12065 -0.2794)
			(end -0.12065 -0.3048)
			(stroke
				(width 0.1)
				(type default)
			)
			(layer "B.Fab")
		)
		(fp_line
			(start 0.12065 -0.2794)
			(end -0.12065 -0.2794)
			(stroke
				(width 0.1)
				(type default)
			)
			(layer "B.Fab")
		)
		(fp_line
			(start -0.67945 -0.3048)
			(end -0.67945 0.3048)
			(stroke
				(width 0.1)
				(type default)
			)
			(layer "B.Fab")
		)
		(fp_line
			(start -0.12065 -0.3048)
			(end -0.67945 -0.3048)
			(stroke
				(width 0.1)
				(type default)
			)
			(layer "B.Fab")
		)
		(fp_line
			(start 0.12065 -0.305054)
			(end 0.12065 -0.2794)
			(stroke
				(width 0.1)
				(type default)
			)
			(layer "B.Fab")
		)
		(fp_line
			(start 0.67945 -0.305054)
			(end 0.12065 -0.305054)
			(stroke
				(width 0.1)
				(type default)
			)
			(layer "B.Fab")
		)
		(pad "1" smd circle
			(at 0.40005 0 90)
			(size 0 0)
			(layers "B.Cu" "B.Mask" "B.Paste")
			(net "RST_PLD_CPU0_DRAM_EF_N")
		)
		(pad "2" smd circle
			(at -0.40005 0 90)
			(size 0 0)
			(layers "B.Cu" "B.Mask" "B.Paste")
			(net "GND")
		)
	)
	(footprint ""
		(layer "B.Cu")
		(at 126.041912 -328.298048 -90)
		(property "Reference" "PC520_P1_5"
			(at 0 0 90)
			(layer "B.SilkS")
			(hide yes)
			(effects
				(font
					(size 1.27 1.27)
				)
				(justify mirror)
			)
		)
		(property "Value" ""
			(at 0 0 90)
			(layer "B.Fab")
			(effects
				(font
					(size 1.27 1.27)
				)
				(justify mirror)
			)
		)
		(duplicate_pad_numbers_are_jumpers no)
		(fp_line
			(start -1.524 0.762)
			(end 1.524 0.762)
			(stroke
				(width 0.1524)
				(type default)
			)
			(layer "B.SilkS")
		)
		(fp_line
			(start 1.524 0.762)
			(end 1.524 -0.762)
			(stroke
				(width 0.1524)
				(type default)
			)
			(layer "B.SilkS")
		)
		(fp_line
			(start -1.524 -0.762)
			(end -1.524 0.762)
			(stroke
				(width 0.1524)
				(type default)
			)
			(layer "B.SilkS")
		)
		(fp_line
			(start 1.524 -0.762)
			(end -1.524 -0.762)
			(stroke
				(width 0.1524)
				(type default)
			)
			(layer "B.SilkS")
		)
		(fp_line
			(start -1.1049 0.724916)
			(end -1.1049 -0.724916)
			(stroke
				(width 0.1)
				(type default)
			)
			(layer "B.Fab")
		)
		(fp_line
			(start 1.1049 0.724916)
			(end -1.1049 0.724916)
			(stroke
				(width 0.1)
				(type default)
			)
			(layer "B.Fab")
		)
		(fp_line
			(start -1.1049 -0.724916)
			(end 1.1049 -0.724916)
			(stroke
				(width 0.1)
				(type default)
			)
			(layer "B.Fab")
		)
		(fp_line
			(start 1.1049 -0.724916)
			(end 1.1049 0.724916)
			(stroke
				(width 0.1)
				(type default)
			)
			(layer "B.Fab")
		)
		(pad "1" smd rect
			(at 0.889 0 270)
			(size 1.016 1.27)
			(layers "B.Cu" "B.Mask" "B.Paste")
			(net "PVCCIN_CPU1")
		)
		(pad "2" smd rect
			(at -0.889 0 270)
			(size 1.016 1.27)
			(layers "B.Cu" "B.Mask" "B.Paste")
			(net "GND")
		)
	)
	(footprint ""
		(layer "B.Cu")
		(at 309.5498 -34.1884 180)
		(property "Reference" "R4768"
			(at 0 0 0)
			(layer "B.SilkS")
			(hide yes)
			(effects
				(font
					(size 1.27 1.27)
				)
				(justify mirror)
			)
		)
		(property "Value" ""
			(at 0 0 0)
			(layer "B.Fab")
			(effects
				(font
					(size 1.27 1.27)
				)
				(justify mirror)
			)
		)
		(duplicate_pad_numbers_are_jumpers no)
		(fp_line
			(start 0.7874 0.4064)
			(end 0.7874 -0.4064)
			(stroke
				(width 0.1524)
				(type default)
			)
			(layer "B.SilkS")
		)
		(fp_line
			(start 0.7874 -0.4064)
			(end -0.7874 -0.4064)
			(stroke
				(width 0.1524)
				(type default)
			)
			(layer "B.SilkS")
		)
		(fp_line
			(start -0.7874 0.4064)
			(end 0.7874 0.4064)
			(stroke
				(width 0.1524)
				(type default)
			)
			(layer "B.SilkS")
		)
		(fp_line
			(start -0.7874 -0.4064)
			(end -0.7874 0.4064)
			(stroke
				(width 0.1524)
				(type default)
			)
			(layer "B.SilkS")
		)
		(fp_line
			(start 0.67945 0.3048)
			(end 0.67945 -0.305054)
			(stroke
				(width 0.1)
				(type default)
			)
			(layer "B.Fab")
		)
		(fp_line
			(start 0.67945 -0.305054)
			(end 0.12065 -0.305054)
			(stroke
				(width 0.1)
				(type default)
			)
			(layer "B.Fab")
		)
		(fp_line
			(start 0.12065 0.3048)
			(end 0.67945 0.3048)
			(stroke
				(width 0.1)
				(type default)
			)
			(layer "B.Fab")
		)
		(fp_line
			(start 0.12065 0.2794)
			(end 0.12065 0.3048)
			(stroke
				(width 0.1)
				(type default)
			)
			(layer "B.Fab")
		)
		(fp_line
			(start 0.12065 -0.2794)
			(end -0.12065 -0.2794)
			(stroke
				(width 0.1)
				(type default)
			)
			(layer "B.Fab")
		)
		(fp_line
			(start 0.12065 -0.305054)
			(end 0.12065 -0.2794)
			(stroke
				(width 0.1)
				(type default)
			)
			(layer "B.Fab")
		)
		(fp_line
			(start -0.120396 0.3048)
			(end -0.120396 0.2794)
			(stroke
				(width 0.1)
				(type default)
			)
			(layer "B.Fab")
		)
		(fp_line
			(start -0.120396 0.2794)
			(end 0.12065 0.2794)
			(stroke
				(width 0.1)
				(type default)
			)
			(layer "B.Fab")
		)
		(fp_line
			(start -0.12065 -0.2794)
			(end -0.12065 -0.3048)
			(stroke
				(width 0.1)
				(type default)
			)
			(layer "B.Fab")
		)
		(fp_line
			(start -0.12065 -0.3048)
			(end -0.67945 -0.3048)
			(stroke
				(width 0.1)
				(type default)
			)
			(layer "B.Fab")
		)
		(fp_line
			(start -0.67945 0.3048)
			(end -0.120396 0.3048)
			(stroke
				(width 0.1)
				(type default)
			)
			(layer "B.Fab")
		)
		(fp_line
			(start -0.67945 -0.3048)
			(end -0.67945 0.3048)
			(stroke
				(width 0.1)
				(type default)
			)
			(layer "B.Fab")
		)
		(pad "1" smd circle
			(at 0.40005 0)
			(size 0 0)
			(layers "B.Cu" "B.Mask" "B.Paste")
			(net "E1S_0_CLK_OE_N")
		)
		(pad "2" smd circle
			(at -0.40005 0)
			(size 0 0)
			(layers "B.Cu" "B.Mask" "B.Paste")
			(net "P3V3_AUX")
		)
	)
)
